# S9S_MB_2U (Grand Teton) — schematic netlist excerpt (pin names and nets, part order shuffled) for the footprints in the layout excerpt that follows; sources: Cadence DE-HDL packaged netlist, KiCad conversion of 03242023_DA0F0TMBIJ0_F0T_Motherboard_J_brd_V01_OCP.brd

R4016  Q_RES  4.32K 1% CHIP  pkg 0402LF  page 226 : A = P3V3 ; B = P0V62_CPU0_ERRS_VREF
R4047  Q_RES  33.2 1% CHIP  pkg 0402LF  page 225 : A = RST_CPU1_DRAM_CD_PLD_LVT3_R_N ; B = RST_CPU1_DRAM_CD_PLD_LVT3_N

(kicad_pcb
	(version 20260206)
	(generator "pcbnew")
	(generator_version "10.0")
	(general
		(thickness 1.6)
		(legacy_teardrops no)
	)
	(paper "A4")
	(title_block
		(title "03242023_DA0F0TMBIJ0_F0T_Motherboard_J_brd_V01_OCP.brd")
		(comment 1 "Grand Teton / footprints 3829-3830 of 6105")
	)
	(layers
		(0 "F.Cu" signal "TOP")
		(4 "In1.Cu" signal "GND")
		(6 "In2.Cu" signal "IN1")
		(8 "In3.Cu" signal "GND1")
		(10 "In4.Cu" signal "IN2")
		(12 "In5.Cu" signal "GND2")
		(14 "In6.Cu" signal "IN3")
		(16 "In7.Cu" signal "GND3")
		(18 "In8.Cu" signal "VCC")
		(20 "In9.Cu" signal "VCC1")
		(22 "In10.Cu" signal "GND4")
		(24 "In11.Cu" signal "IN4")
		(26 "In12.Cu" signal "GND5")
		(28 "In13.Cu" signal "IN5")
		(30 "In14.Cu" signal "GND6")
		(32 "In15.Cu" signal "IN6")
		(34 "In16.Cu" signal "GND7")
		(2 "B.Cu" signal "BOTTOM")
		(9 "F.Adhes" user "F.Adhesive")
		(11 "B.Adhes" user "B.Adhesive")
		(13 "F.Paste" user "Package Geometry/Pastemask Top")
		(15 "B.Paste" user "Package Geometry/Pastemask Bottom")
		(5 "F.SilkS" user "Ref Des/Silkscreen Top")
		(7 "B.SilkS" user "Ref Des/Silkscreen Bottom")
		(1 "F.Mask" user "Board Geometry/Soldermask Top")
		(3 "B.Mask" user "Board Geometry/Soldermask Bottom")
		(17 "Dwgs.User" user "User.Drawings")
		(19 "Cmts.User" user "User.Comments")
		(21 "Eco1.User" user "User.Eco1")
		(23 "Eco2.User" user "User.Eco2")
		(25 "Edge.Cuts" user "Board Geometry/Outline")
		(27 "Margin" user)
		(31 "F.CrtYd" user "Package Geometry/Place Bound Top")
		(29 "B.CrtYd" user "Package Geometry/Place Bound Bottom")
		(35 "F.Fab" user "Ref Des/Assembly Top")
		(33 "B.Fab" user "Ref Des/Assembly Bottom")
	)
	(footprint ""
		(layer "F.Cu")
		(at 123.19508 -106.238548 -90)
		(property "Reference" "R4047"
			(at 0 0 270)
			(layer "F.SilkS")
			(hide yes)
			(effects
				(font
					(size 1.27 1.27)
				)
			)
		)
		(property "Value" ""
			(at 0 0 270)
			(layer "F.Fab")
			(effects
				(font
					(size 1.27 1.27)
				)
			)
		)
		(duplicate_pad_numbers_are_jumpers no)
		(fp_line
			(start -0.7874 0.4064)
			(end -0.7874 -0.4064)
			(stroke
				(width 0.1524)
				(type default)
			)
			(layer "F.SilkS")
		)
		(fp_line
			(start 0.7874 0.4064)
			(end -0.7874 0.4064)
			(stroke
				(width 0.1524)
				(type default)
			)
			(layer "F.SilkS")
		)
		(fp_line
			(start -0.7874 -0.4064)
			(end 0.7874 -0.4064)
			(stroke
				(width 0.1524)
				(type default)
			)
			(layer "F.SilkS")
		)
		(fp_line
			(start 0.7874 -0.4064)
			(end 0.7874 0.4064)
			(stroke
				(width 0.1524)
				(type default)
			)
			(layer "F.SilkS")
		)
		(fp_line
			(start -0.67945 0.3048)
			(end -0.67945 -0.305054)
			(stroke
				(width 0.1)
				(type default)
			)
			(layer "F.Fab")
		)
		(fp_line
			(start -0.12065 0.3048)
			(end -0.67945 0.3048)
			(stroke
				(width 0.1)
				(type default)
			)
			(layer "F.Fab")
		)
		(fp_line
			(start 0.120396 0.3048)
			(end 0.120396 0.2794)
			(stroke
				(width 0.1)
				(type default)
			)
			(layer "F.Fab")
		)
		(fp_line
			(start 0.67945 0.3048)
			(end 0.120396 0.3048)
			(stroke
				(width 0.1)
				(type default)
			)
			(layer "F.Fab")
		)
		(fp_line
			(start -0.12065 0.2794)
			(end -0.12065 0.3048)
			(stroke
				(width 0.1)
				(type default)
			)
			(layer "F.Fab")
		)
		(fp_line
			(start 0.120396 0.2794)
			(end -0.12065 0.2794)
			(stroke
				(width 0.1)
				(type default)
			)
			(layer "F.Fab")
		)
		(fp_line
			(start -0.12065 -0.2794)
			(end 0.12065 -0.2794)
			(stroke
				(width 0.1)
				(type default)
			)
			(layer "F.Fab")
		)
		(fp_line
			(start 0.12065 -0.2794)
			(end 0.12065 -0.3048)
			(stroke
				(width 0.1)
				(type default)
			)
			(layer "F.Fab")
		)
		(fp_line
			(start 0.12065 -0.3048)
			(end 0.67945 -0.3048)
			(stroke
				(width 0.1)
				(type default)
			)
			(layer "F.Fab")
		)
		(fp_line
			(start 0.67945 -0.3048)
			(end 0.67945 0.3048)
			(stroke
				(width 0.1)
				(type default)
			)
			(layer "F.Fab")
		)
		(fp_line
			(start -0.67945 -0.305054)
			(end -0.12065 -0.305054)
			(stroke
				(width 0.1)
				(type default)
			)
			(layer "F.Fab")
		)
		(fp_line
			(start -0.12065 -0.305054)
			(end -0.12065 -0.2794)
			(stroke
				(width 0.1)
				(type default)
			)
			(layer "F.Fab")
		)
		(pad "1" smd circle
			(at -0.40005 0 270)
			(size 0 0)
			(layers "F.Cu" "F.Mask" "F.Paste")
			(net "RST_CPU1_DRAM_CD_PLD_LVT3_R_N")
		)
		(pad "2" smd circle
			(at 0.40005 0 270)
			(size 0 0)
			(layers "F.Cu" "F.Mask" "F.Paste")
			(net "RST_CPU1_DRAM_CD_PLD_LVT3_N")
		)
	)
	(footprint ""
		(layer "F.Cu")
		(at 115.75288 -101.793548 -90)
		(property "Reference" "R4016"
			(at 0 0 270)
			(layer "F.SilkS")
			(hide yes)
			(effects
				(font
					(size 1.27 1.27)
				)
			)
		)
		(property "Value" ""
			(at 0 0 270)
			(layer "F.Fab")
			(effects
				(font
					(size 1.27 1.27)
				)
			)
		)
		(duplicate_pad_numbers_are_jumpers no)
		(fp_line
			(start -0.7874 0.4064)
			(end -0.7874 -0.4064)
			(stroke
				(width 0.1524)
				(type default)
			)
			(layer "F.SilkS")
		)
		(fp_line
			(start 0.7874 0.4064)
			(end -0.7874 0.4064)
			(stroke
				(width 0.1524)
				(type default)
			)
			(layer "F.SilkS")
		)
		(fp_line
			(start -0.7874 -0.4064)
			(end 0.7874 -0.4064)
			(stroke
				(width 0.1524)
				(type default)
			)
			(layer "F.SilkS")
		)
		(fp_line
			(start 0.7874 -0.4064)
			(end 0.7874 0.4064)
			(stroke
				(width 0.1524)
				(type default)
			)
			(layer "F.SilkS")
		)
		(fp_line
			(start -0.67945 0.3048)
			(end -0.67945 -0.305054)
			(stroke
				(width 0.1)
				(type default)
			)
			(layer "F.Fab")
		)
		(fp_line
			(start -0.12065 0.3048)
			(end -0.67945 0.3048)
			(stroke
				(width 0.1)
				(type default)
			)
			(layer "F.Fab")
		)
		(fp_line
			(start 0.120396 0.3048)
			(end 0.120396 0.2794)
			(stroke
				(width 0.1)
				(type default)
			)
			(layer "F.Fab")
		)
		(fp_line
			(start 0.67945 0.3048)
			(end 0.120396 0.3048)
			(stroke
				(width 0.1)
				(type default)
			)
			(layer "F.Fab")
		)
		(fp_line
			(start -0.12065 0.2794)
			(end -0.12065 0.3048)
			(stroke
				(width 0.1)
				(type default)
			)
			(layer "F.Fab")
		)
		(fp_line
			(start 0.120396 0.2794)
			(end -0.12065 0.2794)
			(stroke
				(width 0.1)
				(type default)
			)
			(layer "F.Fab")
		)
		(fp_line
			(start -0.12065 -0.2794)
			(end 0.12065 -0.2794)
			(stroke
				(width 0.1)
				(type default)
			)
			(layer "F.Fab")
		)
		(fp_line
			(start 0.12065 -0.2794)
			(end 0.12065 -0.3048)
			(stroke
				(width 0.1)
				(type default)
			)
			(layer "F.Fab")
		)
		(fp_line
			(start 0.12065 -0.3048)
			(end 0.67945 -0.3048)
			(stroke
				(width 0.1)
				(type default)
			)
			(layer "F.Fab")
		)
		(fp_line
			(start 0.67945 -0.3048)
			(end 0.67945 0.3048)
			(stroke
				(width 0.1)
				(type default)
			)
			(layer "F.Fab")
		)
		(fp_line
			(start -0.67945 -0.305054)
			(end -0.12065 -0.305054)
			(stroke
				(width 0.1)
				(type default)
			)
			(layer "F.Fab")
		)
		(fp_line
			(start -0.12065 -0.305054)
			(end -0.12065 -0.2794)
			(stroke
				(width 0.1)
				(type default)
			)
			(layer "F.Fab")
		)
		(pad "1" smd circle
			(at -0.40005 0 270)
			(size 0 0)
			(layers "F.Cu" "F.Mask" "F.Paste")
			(net "P3V3")
		)
		(pad "2" smd circle
			(at 0.40005 0 270)
			(size 0 0)
			(layers "F.Cu" "F.Mask" "F.Paste")
			(net "P0V62_CPU0_ERRS_VREF")
		)
	)
)
